# S9S_MB_2U (Grand Teton) — schematic netlist excerpt (pin names and nets, part order shuffled) for the footprints in the layout excerpt that follows; sources: Cadence DE-HDL packaged netlist, KiCad conversion of 03242023_DA0F0TMBIJ0_F0T_Motherboard_J_brd_V01_OCP.brd

R1289  Q_RES  100K 1% CHIP  pkg 0402LF  page 154 : A = FB_BMC_ISOLATE ; B = GND
PC548  Q_CAP  0.1UF 25V 10% X7R  pkg 0402  page 284 : A = PVCCIN_CPU1_VIN_CSNIN ; B = GND
C235  Q_CAP  47UF 4V 20% X6S  pkg C0805  page 77 : A = PVCCIN_CPU1 ; B = GND

(kicad_pcb
	(version 20260206)
	(generator "pcbnew")
	(generator_version "10.0")
	(general
		(thickness 1.6)
		(legacy_teardrops no)
	)
	(paper "A4")
	(title_block
		(title "03242023_DA0F0TMBIJ0_F0T_Motherboard_J_brd_V01_OCP.brd")
		(comment 1 "Grand Teton / footprints 3931-3933 of 6105")
	)
	(layers
		(0 "F.Cu" signal "TOP")
		(4 "In1.Cu" signal "GND")
		(6 "In2.Cu" signal "IN1")
		(8 "In3.Cu" signal "GND1")
		(10 "In4.Cu" signal "IN2")
		(12 "In5.Cu" signal "GND2")
		(14 "In6.Cu" signal "IN3")
		(16 "In7.Cu" signal "GND3")
		(18 "In8.Cu" signal "VCC")
		(20 "In9.Cu" signal "VCC1")
		(22 "In10.Cu" signal "GND4")
		(24 "In11.Cu" signal "IN4")
		(26 "In12.Cu" signal "GND5")
		(28 "In13.Cu" signal "IN5")
		(30 "In14.Cu" signal "GND6")
		(32 "In15.Cu" signal "IN6")
		(34 "In16.Cu" signal "GND7")
		(2 "B.Cu" signal "BOTTOM")
		(9 "F.Adhes" user "F.Adhesive")
		(11 "B.Adhes" user "B.Adhesive")
		(13 "F.Paste" user "Package Geometry/Pastemask Top")
		(15 "B.Paste" user "Package Geometry/Pastemask Bottom")
		(5 "F.SilkS" user "Ref Des/Silkscreen Top")
		(7 "B.SilkS" user "Ref Des/Silkscreen Bottom")
		(1 "F.Mask" user "Board Geometry/Soldermask Top")
		(3 "B.Mask" user "Board Geometry/Soldermask Bottom")
		(17 "Dwgs.User" user "User.Drawings")
		(19 "Cmts.User" user "User.Comments")
		(21 "Eco1.User" user "User.Eco1")
		(23 "Eco2.User" user "User.Eco2")
		(25 "Edge.Cuts" user "Board Geometry/Outline")
		(27 "Margin" user)
		(31 "F.CrtYd" user "Package Geometry/Place Bound Top")
		(29 "B.CrtYd" user "Package Geometry/Place Bound Bottom")
		(35 "F.Fab" user "Ref Des/Assembly Top")
		(33 "B.Fab" user "Ref Des/Assembly Bottom")
	)
	(footprint ""
		(layer "F.Cu")
		(at 114.706654 -360.83875)
		(property "Reference" "PC548"
			(at 0 0 0)
			(layer "F.SilkS")
			(hide yes)
			(effects
				(font
					(size 1.27 1.27)
				)
			)
		)
		(property "Value" ""
			(at 0 0 0)
			(layer "F.Fab")
			(effects
				(font
					(size 1.27 1.27)
				)
			)
		)
		(duplicate_pad_numbers_are_jumpers no)
		(fp_line
			(start -0.7874 -0.4064)
			(end 0.7874 -0.4064)
			(stroke
				(width 0.1524)
				(type default)
			)
			(layer "F.SilkS")
		)
		(fp_line
			(start -0.7874 0.4064)
			(end -0.7874 -0.4064)
			(stroke
				(width 0.1524)
				(type default)
			)
			(layer "F.SilkS")
		)
		(fp_line
			(start 0.7874 -0.4064)
			(end 0.7874 0.4064)
			(stroke
				(width 0.1524)
				(type default)
			)
			(layer "F.SilkS")
		)
		(fp_line
			(start 0.7874 0.4064)
			(end -0.7874 0.4064)
			(stroke
				(width 0.1524)
				(type default)
			)
			(layer "F.SilkS")
		)
		(fp_line
			(start -0.67945 -0.305054)
			(end -0.12065 -0.305054)
			(stroke
				(width 0.1)
				(type default)
			)
			(layer "F.Fab")
		)
		(fp_line
			(start -0.67945 0.3048)
			(end -0.67945 -0.305054)
			(stroke
				(width 0.1)
				(type default)
			)
			(layer "F.Fab")
		)
		(fp_line
			(start -0.12065 -0.305054)
			(end -0.12065 -0.2794)
			(stroke
				(width 0.1)
				(type default)
			)
			(layer "F.Fab")
		)
		(fp_line
			(start -0.12065 -0.2794)
			(end 0.12065 -0.2794)
			(stroke
				(width 0.1)
				(type default)
			)
			(layer "F.Fab")
		)
		(fp_line
			(start -0.12065 0.2794)
			(end -0.12065 0.3048)
			(stroke
				(width 0.1)
				(type default)
			)
			(layer "F.Fab")
		)
		(fp_line
			(start -0.12065 0.3048)
			(end -0.67945 0.3048)
			(stroke
				(width 0.1)
				(type default)
			)
			(layer "F.Fab")
		)
		(fp_line
			(start 0.120396 0.2794)
			(end -0.12065 0.2794)
			(stroke
				(width 0.1)
				(type default)
			)
			(layer "F.Fab")
		)
		(fp_line
			(start 0.120396 0.3048)
			(end 0.120396 0.2794)
			(stroke
				(width 0.1)
				(type default)
			)
			(layer "F.Fab")
		)
		(fp_line
			(start 0.12065 -0.3048)
			(end 0.67945 -0.3048)
			(stroke
				(width 0.1)
				(type default)
			)
			(layer "F.Fab")
		)
		(fp_line
			(start 0.12065 -0.2794)
			(end 0.12065 -0.3048)
			(stroke
				(width 0.1)
				(type default)
			)
			(layer "F.Fab")
		)
		(fp_line
			(start 0.67945 -0.3048)
			(end 0.67945 0.3048)
			(stroke
				(width 0.1)
				(type default)
			)
			(layer "F.Fab")
		)
		(fp_line
			(start 0.67945 0.3048)
			(end 0.120396 0.3048)
			(stroke
				(width 0.1)
				(type default)
			)
			(layer "F.Fab")
		)
		(pad "1" smd circle
			(at -0.40005 0)
			(size 0 0)
			(layers "F.Cu" "F.Mask" "F.Paste")
			(net "PVCCIN_CPU1_VIN_CSNIN")
		)
		(pad "2" smd circle
			(at 0.40005 0)
			(size 0 0)
			(layers "F.Cu" "F.Mask" "F.Paste")
			(net "GND")
		)
	)
	(footprint ""
		(layer "F.Cu")
		(at 466.5345 -96.007682 -90)
		(property "Reference" "R1289"
			(at 0 0 270)
			(layer "F.SilkS")
			(hide yes)
			(effects
				(font
					(size 1.27 1.27)
				)
			)
		)
		(property "Value" ""
			(at 0 0 270)
			(layer "F.Fab")
			(effects
				(font
					(size 1.27 1.27)
				)
			)
		)
		(duplicate_pad_numbers_are_jumpers no)
		(fp_line
			(start -0.7874 0.4064)
			(end -0.7874 -0.4064)
			(stroke
				(width 0.1524)
				(type default)
			)
			(layer "F.SilkS")
		)
		(fp_line
			(start 0.7874 0.4064)
			(end -0.7874 0.4064)
			(stroke
				(width 0.1524)
				(type default)
			)
			(layer "F.SilkS")
		)
		(fp_line
			(start -0.7874 -0.4064)
			(end 0.7874 -0.4064)
			(stroke
				(width 0.1524)
				(type default)
			)
			(layer "F.SilkS")
		)
		(fp_line
			(start 0.7874 -0.4064)
			(end 0.7874 0.4064)
			(stroke
				(width 0.1524)
				(type default)
			)
			(layer "F.SilkS")
		)
		(fp_line
			(start -0.67945 0.3048)
			(end -0.67945 -0.305054)
			(stroke
				(width 0.1)
				(type default)
			)
			(layer "F.Fab")
		)
		(fp_line
			(start -0.12065 0.3048)
			(end -0.67945 0.3048)
			(stroke
				(width 0.1)
				(type default)
			)
			(layer "F.Fab")
		)
		(fp_line
			(start 0.120396 0.3048)
			(end 0.120396 0.2794)
			(stroke
				(width 0.1)
				(type default)
			)
			(layer "F.Fab")
		)
		(fp_line
			(start 0.67945 0.3048)
			(end 0.120396 0.3048)
			(stroke
				(width 0.1)
				(type default)
			)
			(layer "F.Fab")
		)
		(fp_line
			(start -0.12065 0.2794)
			(end -0.12065 0.3048)
			(stroke
				(width 0.1)
				(type default)
			)
			(layer "F.Fab")
		)
		(fp_line
			(start 0.120396 0.2794)
			(end -0.12065 0.2794)
			(stroke
				(width 0.1)
				(type default)
			)
			(layer "F.Fab")
		)
		(fp_line
			(start -0.12065 -0.2794)
			(end 0.12065 -0.2794)
			(stroke
				(width 0.1)
				(type default)
			)
			(layer "F.Fab")
		)
		(fp_line
			(start 0.12065 -0.2794)
			(end 0.12065 -0.3048)
			(stroke
				(width 0.1)
				(type default)
			)
			(layer "F.Fab")
		)
		(fp_line
			(start 0.12065 -0.3048)
			(end 0.67945 -0.3048)
			(stroke
				(width 0.1)
				(type default)
			)
			(layer "F.Fab")
		)
		(fp_line
			(start 0.67945 -0.3048)
			(end 0.67945 0.3048)
			(stroke
				(width 0.1)
				(type default)
			)
			(layer "F.Fab")
		)
		(fp_line
			(start -0.67945 -0.305054)
			(end -0.12065 -0.305054)
			(stroke
				(width 0.1)
				(type default)
			)
			(layer "F.Fab")
		)
		(fp_line
			(start -0.12065 -0.305054)
			(end -0.12065 -0.2794)
			(stroke
				(width 0.1)
				(type default)
			)
			(layer "F.Fab")
		)
		(pad "1" smd circle
			(at -0.40005 0 270)
			(size 0 0)
			(layers "F.Cu" "F.Mask" "F.Paste")
			(net "FB_BMC_ISOLATE")
		)
		(pad "2" smd circle
			(at 0.40005 0 270)
			(size 0 0)
			(layers "F.Cu" "F.Mask" "F.Paste")
			(net "GND")
		)
	)
	(footprint ""
		(layer "F.Cu")
		(at 114.91722 -294.01008)
		(property "Reference" "C235"
			(at 0 0 0)
			(layer "F.SilkS")
			(hide yes)
			(effects
				(font
					(size 1.27 1.27)
				)
			)
		)
		(property "Value" ""
			(at 0 0 0)
			(layer "F.Fab")
			(effects
				(font
					(size 1.27 1.27)
				)
			)
		)
		(duplicate_pad_numbers_are_jumpers no)
		(fp_line
			(start -1.524 -0.762)
			(end 1.524 -0.762)
			(stroke
				(width 0.1524)
				(type default)
			)
			(layer "F.SilkS")
		)
		(fp_line
			(start -1.524 0.762)
			(end -1.524 -0.762)
			(stroke
				(width 0.1524)
				(type default)
			)
			(layer "F.SilkS")
		)
		(fp_line
			(start 1.524 -0.762)
			(end 1.524 0.762)
			(stroke
				(width 0.1524)
				(type default)
			)
			(layer "F.SilkS")
		)
		(fp_line
			(start 1.524 0.762)
			(end -1.524 0.762)
			(stroke
				(width 0.1524)
				(type default)
			)
			(layer "F.SilkS")
		)
		(fp_line
			(start -1.1049 -0.724916)
			(end -1.1049 0.724916)
			(stroke
				(width 0.1)
				(type default)
			)
			(layer "F.Fab")
		)
		(fp_line
			(start -1.1049 0.724916)
			(end 1.1049 0.724916)
			(stroke
				(width 0.1)
				(type default)
			)
			(layer "F.Fab")
		)
		(fp_line
			(start 1.1049 -0.724916)
			(end -1.1049 -0.724916)
			(stroke
				(width 0.1)
				(type default)
			)
			(layer "F.Fab")
		)
		(fp_line
			(start 1.1049 0.724916)
			(end 1.1049 -0.724916)
			(stroke
				(width 0.1)
				(type default)
			)
			(layer "F.Fab")
		)
		(pad "1" smd rect
			(at -0.889 0 180)
			(size 1.016 1.27)
			(layers "F.Cu" "F.Mask" "F.Paste")
			(net "PVCCIN_CPU1")
		)
		(pad "2" smd rect
			(at 0.889 0 180)
			(size 1.016 1.27)
			(layers "F.Cu" "F.Mask" "F.Paste")
			(net "GND")
		)
	)
)
